(kicad_pcb
	(version 20260206)
	(generator "pcbnew")
	(generator_version "10.0")
	(general
		(thickness 1.6)
		(legacy_teardrops no)
	)
	(paper "A4")
	(title_block
		(title "baseboard — 13948-1b.1110WZS1818.brd")
		(comment 1 "Honey Badger (Wiwynn) / footprint 1078 of 2523 (SU1), pads 465-582 of 672")
	)
	(layers
		(0 "F.Cu" signal "TOP")
		(4 "In1.Cu" signal "L2GND")
		(6 "In2.Cu" signal "L3")
		(8 "In3.Cu" signal "L4VCC")
		(10 "In4.Cu" signal "L5VCC")
		(12 "In5.Cu" signal "L6")
		(14 "In6.Cu" signal "L7GND")
		(2 "B.Cu" signal "BOTTOM")
		(9 "F.Adhes" user "F.Adhesive")
		(11 "B.Adhes" user "B.Adhesive")
		(13 "F.Paste" user "Package Geometry/Pastemask Top")
		(15 "B.Paste" user "Package Geometry/Pastemask Bottom")
		(5 "F.SilkS" user "Ref Des/Silkscreen Top")
		(7 "B.SilkS" user "Ref Des/Silkscreen Bottom")
		(1 "F.Mask" user "Board Geometry/Soldermask Top")
		(3 "B.Mask" user "Board Geometry/Soldermask Bottom")
		(17 "Dwgs.User" user "User.Drawings")
		(19 "Cmts.User" user "User.Comments")
		(21 "Eco1.User" user "User.Eco1")
		(23 "Eco2.User" user "User.Eco2")
		(25 "Edge.Cuts" user "Board Geometry/Outline")
		(27 "Margin" user)
		(31 "F.CrtYd" user "Package Geometry/Place Bound Top")
		(29 "B.CrtYd" user "Package Geometry/Place Bound Bottom")
		(35 "F.Fab" user "Ref Des/Assembly Top")
		(33 "B.Fab" user "Ref Des/Assembly Bottom")
	)
	(footprint ""
		(layer "F.Cu")
		(at 114.84991 -94.84995 90)
		(property "Reference" "SU1"
			(at 0 0 90)
			(layer "F.SilkS")
			(hide yes)
			(effects
				(font
					(size 1.27 1.27)
				)
			)
		)
		(property "Value" "SAS3X24RLC1-DB-500021106-GP"
			(at -21.4503 -7.4168 90)
			(unlocked yes)
			(layer "F.Fab")
			(hide yes)
			(effects
				(font
					(size 1.016 1.016)
					(thickness 0.1524)
				)
			)
		)
		(property "Device Type" "BGA672C27H83"
			(at -21.4503 -8.9408 90)
			(unlocked yes)
			(layer "F.Fab")
			(hide yes)
			(effects
				(font
					(size 1.016 1.016)
					(thickness 0.1524)
				)
			)
		)
		(duplicate_pad_numbers_are_jumpers no)
		(pad "N1" smd circle
			(at -12.500102 -0.500126 90)
			(size 0.4572 0.4572)
			(layers "F.Cu" "F.Mask" "F.Paste")
			(net "EXP_TEST_MUX29")
		)
		(pad "N2" smd circle
			(at -11.500104 -0.500126 90)
			(size 0.4572 0.4572)
			(layers "F.Cu" "F.Mask" "F.Paste")
			(net "EXP_TEST_MUX27")
		)
		(pad "N3" smd circle
			(at -10.500106 -0.500126 90)
			(size 0.4572 0.4572)
			(layers "F.Cu" "F.Mask" "F.Paste")
			(net "P1V8_E")
		)
		(pad "N4" smd circle
			(at -9.500108 -0.500126 90)
			(size 0.4572 0.4572)
			(layers "F.Cu" "F.Mask" "F.Paste")
			(net "EXP_TEST_MUX24")
		)
		(pad "N5" smd circle
			(at -8.50011 -0.500126 90)
			(size 0.4572 0.4572)
			(layers "F.Cu" "F.Mask" "F.Paste")
			(net "SAS_HDD_LED22")
		)
		(pad "N6" smd circle
			(at -7.500112 -0.500126 90)
			(size 0.4572 0.4572)
			(layers "F.Cu" "F.Mask" "F.Paste")
			(net "GND")
		)
		(pad "N7" smd circle
			(at -6.500114 -0.500126 90)
			(size 0.4572 0.4572)
			(layers "F.Cu" "F.Mask" "F.Paste")
			(net "PLLDDR_VDDA18")
		)
		(pad "N8" smd circle
			(at -5.500116 -0.500126 90)
			(size 0.4572 0.4572)
			(layers "F.Cu" "F.Mask" "F.Paste")
			(net "GND")
		)
		(pad "N9" smd circle
			(at -4.500118 -0.500126 90)
			(size 0.4572 0.4572)
			(layers "F.Cu" "F.Mask" "F.Paste")
			(net "GND")
		)
		(pad "N10" smd circle
			(at -3.50012 -0.500126 90)
			(size 0.4572 0.4572)
			(layers "F.Cu" "F.Mask" "F.Paste")
			(net "P0V9_E")
		)
		(pad "N11" smd circle
			(at -2.500122 -0.500126 90)
			(size 0.4572 0.4572)
			(layers "F.Cu" "F.Mask" "F.Paste")
			(net "GND")
		)
		(pad "N12" smd circle
			(at -1.500124 -0.500126 90)
			(size 0.4572 0.4572)
			(layers "F.Cu" "F.Mask" "F.Paste")
			(net "P0V9_E")
		)
		(pad "N13" smd circle
			(at -0.500126 -0.500126 90)
			(size 0.4572 0.4572)
			(layers "F.Cu" "F.Mask" "F.Paste")
			(net "GND")
		)
		(pad "N14" smd circle
			(at 0.500126 -0.500126 90)
			(size 0.4572 0.4572)
			(layers "F.Cu" "F.Mask" "F.Paste")
			(net "P0V9_E")
		)
		(pad "N15" smd circle
			(at 1.500124 -0.500126 90)
			(size 0.4572 0.4572)
			(layers "F.Cu" "F.Mask" "F.Paste")
			(net "GND")
		)
		(pad "N16" smd circle
			(at 2.500122 -0.500126 90)
			(size 0.4572 0.4572)
			(layers "F.Cu" "F.Mask" "F.Paste")
			(net "P0V9_E")
		)
		(pad "N17" smd circle
			(at 3.50012 -0.500126 90)
			(size 0.4572 0.4572)
			(layers "F.Cu" "F.Mask" "F.Paste")
			(net "GND")
		)
		(pad "N18" smd circle
			(at 4.500118 -0.500126 90)
			(size 0.4572 0.4572)
			(layers "F.Cu" "F.Mask" "F.Paste")
			(net "GND")
		)
		(pad "N19" smd circle
			(at 5.500116 -0.500126 90)
			(size 0.4572 0.4572)
			(layers "F.Cu" "F.Mask" "F.Paste")
			(net "GB_VDDH2")
		)
		(pad "N20" smd circle
			(at 6.500114 -0.500126 90)
			(size 0.4572 0.4572)
			(layers "F.Cu" "F.Mask" "F.Paste")
			(net "GND")
		)
		(pad "N21" smd circle
			(at 7.500112 -0.500126 90)
			(size 0.4572 0.4572)
			(layers "F.Cu" "F.Mask" "F.Paste")
			(net "SAS_HDD_CONN_RX8_N")
		)
		(pad "N22" smd circle
			(at 8.50011 -0.500126 90)
			(size 0.4572 0.4572)
			(layers "F.Cu" "F.Mask" "F.Paste")
			(net "SAS_HDD_CONN_RX8_P")
		)
		(pad "N23" smd circle
			(at 9.500108 -0.500126 90)
			(size 0.4572 0.4572)
			(layers "F.Cu" "F.Mask" "F.Paste")
			(net "GB_VDDA")
		)
		(pad "N24" smd circle
			(at 10.500106 -0.500126 90)
			(size 0.4572 0.4572)
			(layers "F.Cu" "F.Mask" "F.Paste")
			(net "SAS_HDD_TX4_N")
		)
		(pad "N25" smd circle
			(at 11.500104 -0.500126 90)
			(size 0.4572 0.4572)
			(layers "F.Cu" "F.Mask" "F.Paste")
			(net "SAS_HDD_TX4_P")
		)
		(pad "N26" smd circle
			(at 12.500102 -0.500126 90)
			(size 0.4572 0.4572)
			(layers "F.Cu" "F.Mask" "F.Paste")
			(net "GND")
		)
		(pad "P1" smd circle
			(at -12.500102 0.500126 90)
			(size 0.4572 0.4572)
			(layers "F.Cu" "F.Mask" "F.Paste")
			(net "EXP_TEST_MUX32")
		)
		(pad "P2" smd circle
			(at -11.500104 0.500126 90)
			(size 0.4572 0.4572)
			(layers "F.Cu" "F.Mask" "F.Paste")
			(net "EXP_TEST_MUX33")
		)
		(pad "P3" smd circle
			(at -10.500106 0.500126 90)
			(size 0.4572 0.4572)
			(layers "F.Cu" "F.Mask" "F.Paste")
			(net "GND")
		)
		(pad "P4" smd circle
			(at -9.500108 0.500126 90)
			(size 0.4572 0.4572)
			(layers "F.Cu" "F.Mask" "F.Paste")
			(net "EXP_TEST_MUX30")
		)
		(pad "P5" smd circle
			(at -8.50011 0.500126 90)
			(size 0.4572 0.4572)
			(layers "F.Cu" "F.Mask" "F.Paste")
			(net "SAS_HDD_LED21")
		)
		(pad "P6" smd circle
			(at -7.500112 0.500126 90)
			(size 0.4572 0.4572)
			(layers "F.Cu" "F.Mask" "F.Paste")
			(net "P1V8_E")
		)
		(pad "P7" smd circle
			(at -6.500114 0.500126 90)
			(size 0.4572 0.4572)
			(layers "F.Cu" "F.Mask" "F.Paste")
			(net "SAS_ACTIVITY_LED16")
		)
		(pad "P8" smd circle
			(at -5.500116 0.500126 90)
			(size 0.4572 0.4572)
			(layers "F.Cu" "F.Mask" "F.Paste")
			(net "GND")
		)
		(pad "P9" smd circle
			(at -4.500118 0.500126 90)
			(size 0.4572 0.4572)
			(layers "F.Cu" "F.Mask" "F.Paste")
			(net "P0V9_E")
		)
		(pad "P10" smd circle
			(at -3.50012 0.500126 90)
			(size 0.4572 0.4572)
			(layers "F.Cu" "F.Mask" "F.Paste")
			(net "GND")
		)
		(pad "P11" smd circle
			(at -2.500122 0.500126 90)
			(size 0.4572 0.4572)
			(layers "F.Cu" "F.Mask" "F.Paste")
			(net "P0V9_E")
		)
		(pad "P12" smd circle
			(at -1.500124 0.500126 90)
			(size 0.4572 0.4572)
			(layers "F.Cu" "F.Mask" "F.Paste")
			(net "GND")
		)
		(pad "P13" smd circle
			(at -0.500126 0.500126 90)
			(size 0.4572 0.4572)
			(layers "F.Cu" "F.Mask" "F.Paste")
			(net "P0V9_E")
		)
		(pad "P14" smd circle
			(at 0.500126 0.500126 90)
			(size 0.4572 0.4572)
			(layers "F.Cu" "F.Mask" "F.Paste")
			(net "GND")
		)
		(pad "P15" smd circle
			(at 1.500124 0.500126 90)
			(size 0.4572 0.4572)
			(layers "F.Cu" "F.Mask" "F.Paste")
			(net "P0V9_E")
		)
		(pad "P16" smd circle
			(at 2.500122 0.500126 90)
			(size 0.4572 0.4572)
			(layers "F.Cu" "F.Mask" "F.Paste")
			(net "GND")
		)
		(pad "P17" smd circle
			(at 3.50012 0.500126 90)
			(size 0.4572 0.4572)
			(layers "F.Cu" "F.Mask" "F.Paste")
			(net "P0V9_E")
		)
		(pad "P18" smd circle
			(at 4.500118 0.500126 90)
			(size 0.4572 0.4572)
			(layers "F.Cu" "F.Mask" "F.Paste")
			(net "GND")
		)
		(pad "P19" smd circle
			(at 5.500116 0.500126 90)
			(size 0.4572 0.4572)
			(layers "F.Cu" "F.Mask" "F.Paste")
			(net "GB_VDDH2")
		)
		(pad "P20" smd circle
			(at 6.500114 0.500126 90)
			(size 0.4572 0.4572)
			(layers "F.Cu" "F.Mask" "F.Paste")
			(net "GND")
		)
		(pad "P21" smd circle
			(at 7.500112 0.500126 90)
			(size 0.4572 0.4572)
			(layers "F.Cu" "F.Mask" "F.Paste")
			(net "SAS_HDD_CONN_RX7_N")
		)
		(pad "P22" smd circle
			(at 8.50011 0.500126 90)
			(size 0.4572 0.4572)
			(layers "F.Cu" "F.Mask" "F.Paste")
			(net "SAS_HDD_CONN_RX7_P")
		)
		(pad "P23" smd circle
			(at 9.500108 0.500126 90)
			(size 0.4572 0.4572)
			(layers "F.Cu" "F.Mask" "F.Paste")
			(net "GND")
		)
		(pad "P24" smd circle
			(at 10.500106 0.500126 90)
			(size 0.4572 0.4572)
			(layers "F.Cu" "F.Mask" "F.Paste")
			(net "GB_VDDA")
		)
		(pad "P25" smd circle
			(at 11.500104 0.500126 90)
			(size 0.4572 0.4572)
			(layers "F.Cu" "F.Mask" "F.Paste")
			(net "SAS_HDD_TX3_N")
		)
		(pad "P26" smd circle
			(at 12.500102 0.500126 90)
			(size 0.4572 0.4572)
			(layers "F.Cu" "F.Mask" "F.Paste")
			(net "SAS_HDD_TX3_P")
		)
		(pad "R1" smd circle
			(at -12.500102 1.500124 90)
			(size 0.4572 0.4572)
			(layers "F.Cu" "F.Mask" "F.Paste")
			(net "EXP_TEST_MUX34")
		)
		(pad "R2" smd circle
			(at -11.500104 1.500124 90)
			(size 0.4572 0.4572)
			(layers "F.Cu" "F.Mask" "F.Paste")
			(net "EXP_TEST_MUX35")
		)
		(pad "R3" smd circle
			(at -10.500106 1.500124 90)
			(size 0.4572 0.4572)
			(layers "F.Cu" "F.Mask" "F.Paste")
			(net "P1V8_E")
		)
		(pad "R4" smd circle
			(at -9.500108 1.500124 90)
			(size 0.4572 0.4572)
			(layers "F.Cu" "F.Mask" "F.Paste")
			(net "TEST_MUX_38")
		)
		(pad "R5" smd circle
			(at -8.50011 1.500124 90)
			(size 0.4572 0.4572)
			(layers "F.Cu" "F.Mask" "F.Paste")
			(net "EXP_TEST_MUX26")
		)
		(pad "R6" smd circle
			(at -7.500112 1.500124 90)
			(size 0.4572 0.4572)
			(layers "F.Cu" "F.Mask" "F.Paste")
			(net "GND")
		)
		(pad "R7" smd circle
			(at -6.500114 1.500124 90)
			(size 0.4572 0.4572)
			(layers "F.Cu" "F.Mask" "F.Paste")
			(net "EXP_TEST_MUX31")
		)
		(pad "R8" smd circle
			(at -5.500116 1.500124 90)
			(size 0.4572 0.4572)
			(layers "F.Cu" "F.Mask" "F.Paste")
			(net "GND")
		)
		(pad "R9" smd circle
			(at -4.500118 1.500124 90)
			(size 0.4572 0.4572)
			(layers "F.Cu" "F.Mask" "F.Paste")
			(net "Net_1132")
		)
		(pad "R10" smd circle
			(at -3.50012 1.500124 90)
			(size 0.4572 0.4572)
			(layers "F.Cu" "F.Mask" "F.Paste")
			(net "P0V9_E")
		)
		(pad "R11" smd circle
			(at -2.500122 1.500124 90)
			(size 0.4572 0.4572)
			(layers "F.Cu" "F.Mask" "F.Paste")
			(net "GND")
		)
		(pad "R12" smd circle
			(at -1.500124 1.500124 90)
			(size 0.4572 0.4572)
			(layers "F.Cu" "F.Mask" "F.Paste")
			(net "P0V9_E")
		)
		(pad "R13" smd circle
			(at -0.500126 1.500124 90)
			(size 0.4572 0.4572)
			(layers "F.Cu" "F.Mask" "F.Paste")
			(net "GND")
		)
		(pad "R14" smd circle
			(at 0.500126 1.500124 90)
			(size 0.4572 0.4572)
			(layers "F.Cu" "F.Mask" "F.Paste")
			(net "P0V9_E")
		)
		(pad "R15" smd circle
			(at 1.500124 1.500124 90)
			(size 0.4572 0.4572)
			(layers "F.Cu" "F.Mask" "F.Paste")
			(net "GND")
		)
		(pad "R16" smd circle
			(at 2.500122 1.500124 90)
			(size 0.4572 0.4572)
			(layers "F.Cu" "F.Mask" "F.Paste")
			(net "P0V9_E")
		)
		(pad "R17" smd circle
			(at 3.50012 1.500124 90)
			(size 0.4572 0.4572)
			(layers "F.Cu" "F.Mask" "F.Paste")
			(net "GND")
		)
		(pad "R18" smd circle
			(at 4.500118 1.500124 90)
			(size 0.4572 0.4572)
			(layers "F.Cu" "F.Mask" "F.Paste")
			(net "GND")
		)
		(pad "R19" smd circle
			(at 5.500116 1.500124 90)
			(size 0.4572 0.4572)
			(layers "F.Cu" "F.Mask" "F.Paste")
			(net "GND")
		)
		(pad "R20" smd circle
			(at 6.500114 1.500124 90)
			(size 0.4572 0.4572)
			(layers "F.Cu" "F.Mask" "F.Paste")
			(net "GND")
		)
		(pad "R21" smd circle
			(at 7.500112 1.500124 90)
			(size 0.4572 0.4572)
			(layers "F.Cu" "F.Mask" "F.Paste")
			(net "SAS_GF_EXP_RX_DN6")
		)
		(pad "R22" smd circle
			(at 8.50011 1.500124 90)
			(size 0.4572 0.4572)
			(layers "F.Cu" "F.Mask" "F.Paste")
			(net "SAS_GF_EXP_RX_DP6")
		)
		(pad "R23" smd circle
			(at 9.500108 1.500124 90)
			(size 0.4572 0.4572)
			(layers "F.Cu" "F.Mask" "F.Paste")
			(net "GB_VDDA")
		)
		(pad "R24" smd circle
			(at 10.500106 1.500124 90)
			(size 0.4572 0.4572)
			(layers "F.Cu" "F.Mask" "F.Paste")
			(net "SAS_HDD_TX2_N")
		)
		(pad "R25" smd circle
			(at 11.500104 1.500124 90)
			(size 0.4572 0.4572)
			(layers "F.Cu" "F.Mask" "F.Paste")
			(net "SAS_HDD_TX2_P")
		)
		(pad "R26" smd circle
			(at 12.500102 1.500124 90)
			(size 0.4572 0.4572)
			(layers "F.Cu" "F.Mask" "F.Paste")
			(net "GND")
		)
		(pad "T1" smd circle
			(at -12.500102 2.500122 90)
			(size 0.4572 0.4572)
			(layers "F.Cu" "F.Mask" "F.Paste")
			(net "TEST_MUX_37")
		)
		(pad "T2" smd circle
			(at -11.500104 2.500122 90)
			(size 0.4572 0.4572)
			(layers "F.Cu" "F.Mask" "F.Paste")
			(net "TEST_MUX_39")
		)
		(pad "T3" smd circle
			(at -10.500106 2.500122 90)
			(size 0.4572 0.4572)
			(layers "F.Cu" "F.Mask" "F.Paste")
			(net "GND")
		)
		(pad "T4" smd circle
			(at -9.500108 2.500122 90)
			(size 0.4572 0.4572)
			(layers "F.Cu" "F.Mask" "F.Paste")
			(net "TEST_MUX_40")
		)
		(pad "T5" smd circle
			(at -8.50011 2.500122 90)
			(size 0.4572 0.4572)
			(layers "F.Cu" "F.Mask" "F.Paste")
			(net "TEST_MUX_36")
		)
		(pad "T6" smd circle
			(at -7.500112 2.500122 90)
			(size 0.4572 0.4572)
			(layers "F.Cu" "F.Mask" "F.Paste")
			(net "P1V8_E")
		)
		(pad "T7" smd circle
			(at -6.500114 2.500122 90)
			(size 0.4572 0.4572)
			(layers "F.Cu" "F.Mask" "F.Paste")
			(net "TEST_MUX_41")
		)
		(pad "T8" smd circle
			(at -5.500116 2.500122 90)
			(size 0.4572 0.4572)
			(layers "F.Cu" "F.Mask" "F.Paste")
			(net "GND")
		)
		(pad "T9" smd circle
			(at -4.500118 2.500122 90)
			(size 0.4572 0.4572)
			(layers "F.Cu" "F.Mask" "F.Paste")
			(net "P0V9_E")
		)
		(pad "T10" smd circle
			(at -3.50012 2.500122 90)
			(size 0.4572 0.4572)
			(layers "F.Cu" "F.Mask" "F.Paste")
			(net "GND")
		)
		(pad "T11" smd circle
			(at -2.500122 2.500122 90)
			(size 0.4572 0.4572)
			(layers "F.Cu" "F.Mask" "F.Paste")
			(net "P0V9_E")
		)
		(pad "T12" smd circle
			(at -1.500124 2.500122 90)
			(size 0.4572 0.4572)
			(layers "F.Cu" "F.Mask" "F.Paste")
			(net "GND")
		)
		(pad "T13" smd circle
			(at -0.500126 2.500122 90)
			(size 0.4572 0.4572)
			(layers "F.Cu" "F.Mask" "F.Paste")
			(net "P0V9_E")
		)
		(pad "T14" smd circle
			(at 0.500126 2.500122 90)
			(size 0.4572 0.4572)
			(layers "F.Cu" "F.Mask" "F.Paste")
			(net "GND")
		)
		(pad "T15" smd circle
			(at 1.500124 2.500122 90)
			(size 0.4572 0.4572)
			(layers "F.Cu" "F.Mask" "F.Paste")
			(net "P0V9_E")
		)
		(pad "T16" smd circle
			(at 2.500122 2.500122 90)
			(size 0.4572 0.4572)
			(layers "F.Cu" "F.Mask" "F.Paste")
			(net "GND")
		)
		(pad "T17" smd circle
			(at 3.50012 2.500122 90)
			(size 0.4572 0.4572)
			(layers "F.Cu" "F.Mask" "F.Paste")
			(net "P0V9_E")
		)
		(pad "T18" smd circle
			(at 4.500118 2.500122 90)
			(size 0.4572 0.4572)
			(layers "F.Cu" "F.Mask" "F.Paste")
			(net "GND")
		)
		(pad "T19" smd circle
			(at 5.500116 2.500122 90)
			(size 0.4572 0.4572)
			(layers "F.Cu" "F.Mask" "F.Paste")
			(net "GND")
		)
		(pad "T20" smd circle
			(at 6.500114 2.500122 90)
			(size 0.4572 0.4572)
			(layers "F.Cu" "F.Mask" "F.Paste")
			(net "GB_VDDA")
		)
		(pad "T21" smd circle
			(at 7.500112 2.500122 90)
			(size 0.4572 0.4572)
			(layers "F.Cu" "F.Mask" "F.Paste")
			(net "SAS_GF_EXP_RX_DN5")
		)
		(pad "T22" smd circle
			(at 8.50011 2.500122 90)
			(size 0.4572 0.4572)
			(layers "F.Cu" "F.Mask" "F.Paste")
			(net "SAS_GF_EXP_RX_DP5")
		)
		(pad "T23" smd circle
			(at 9.500108 2.500122 90)
			(size 0.4572 0.4572)
			(layers "F.Cu" "F.Mask" "F.Paste")
			(net "GND")
		)
		(pad "T24" smd circle
			(at 10.500106 2.500122 90)
			(size 0.4572 0.4572)
			(layers "F.Cu" "F.Mask" "F.Paste")
			(net "GB_VDDA")
		)
		(pad "T25" smd circle
			(at 11.500104 2.500122 90)
			(size 0.4572 0.4572)
			(layers "F.Cu" "F.Mask" "F.Paste")
			(net "SAS_HDD_TX1_N")
		)
		(pad "T26" smd circle
			(at 12.500102 2.500122 90)
			(size 0.4572 0.4572)
			(layers "F.Cu" "F.Mask" "F.Paste")
			(net "SAS_HDD_TX1_P")
		)
		(pad "U1" smd circle
			(at -12.500102 3.50012 90)
			(size 0.4572 0.4572)
			(layers "F.Cu" "F.Mask" "F.Paste")
			(net "TEST_MUX_43")
		)
		(pad "U2" smd circle
			(at -11.500104 3.50012 90)
			(size 0.4572 0.4572)
			(layers "F.Cu" "F.Mask" "F.Paste")
			(net "TEST_MUX_42")
		)
		(pad "U3" smd circle
			(at -10.500106 3.50012 90)
			(size 0.4572 0.4572)
			(layers "F.Cu" "F.Mask" "F.Paste")
			(net "P1V8_E")
		)
		(pad "U4" smd circle
			(at -9.500108 3.50012 90)
			(size 0.4572 0.4572)
			(layers "F.Cu" "F.Mask" "F.Paste")
			(net "TEST_MUX_45")
		)
		(pad "U5" smd circle
			(at -8.50011 3.50012 90)
			(size 0.4572 0.4572)
			(layers "F.Cu" "F.Mask" "F.Paste")
			(net "TEST_MUX_46")
		)
		(pad "U6" smd circle
			(at -7.500112 3.50012 90)
			(size 0.4572 0.4572)
			(layers "F.Cu" "F.Mask" "F.Paste")
			(net "GND")
		)
		(pad "U7" smd circle
			(at -6.500114 3.50012 90)
			(size 0.4572 0.4572)
			(layers "F.Cu" "F.Mask" "F.Paste")
			(net "XTAL_VDDA09")
		)
		(pad "U8" smd circle
			(at -5.500116 3.50012 90)
			(size 0.4572 0.4572)
			(layers "F.Cu" "F.Mask" "F.Paste")
			(net "GND")
		)
		(pad "U9" smd circle
			(at -4.500118 3.50012 90)
			(size 0.4572 0.4572)
			(layers "F.Cu" "F.Mask" "F.Paste")
			(net "GND")
		)
		(pad "U10" smd circle
			(at -3.50012 3.50012 90)
			(size 0.4572 0.4572)
			(layers "F.Cu" "F.Mask" "F.Paste")
			(net "GND")
		)
		(pad "U11" smd circle
			(at -2.500122 3.50012 90)
			(size 0.4572 0.4572)
			(layers "F.Cu" "F.Mask" "F.Paste")
			(net "GND")
		)
		(pad "U12" smd circle
			(at -1.500124 3.50012 90)
			(size 0.4572 0.4572)
			(layers "F.Cu" "F.Mask" "F.Paste")
			(net "GND")
		)
		(pad "U13" smd circle
			(at -0.500126 3.50012 90)
			(size 0.4572 0.4572)
			(layers "F.Cu" "F.Mask" "F.Paste")
			(net "GND")
		)
		(pad "U14" smd circle
			(at 0.500126 3.50012 90)
			(size 0.4572 0.4572)
			(layers "F.Cu" "F.Mask" "F.Paste")
			(net "GND")
		)
	)
)
